(kicad_pcb
	(version 20260206)
	(generator "pcbnew")
	(generator_version "10.0")
	(general
		(thickness 1.6)
		(legacy_teardrops no)
	)
	(paper "A4")
	(title_block
		(title "01162023_DA0F0TEBIF0_F0T_Expander_BD_F_brd_V02_OCP.brd")
		(comment 1 "Grand Teton / footprints 876-882 of 9728")
	)
	(layers
		(0 "F.Cu" signal "TOP")
		(4 "In1.Cu" signal "GND")
		(6 "In2.Cu" signal "VCC")
		(8 "In3.Cu" signal "VCC1")
		(10 "In4.Cu" signal "GND1")
		(12 "In5.Cu" signal "IN1")
		(14 "In6.Cu" signal "GND2")
		(16 "In7.Cu" signal "IN2")
		(18 "In8.Cu" signal "GND3")
		(20 "In9.Cu" signal "IN3")
		(22 "In10.Cu" signal "GND4")
		(24 "In11.Cu" signal "IN4")
		(26 "In12.Cu" signal "GND5")
		(28 "In13.Cu" signal "IN5")
		(30 "In14.Cu" signal "GND6")
		(32 "In15.Cu" signal "IN6")
		(34 "In16.Cu" signal "GND7")
		(2 "B.Cu" signal "BOTTOM")
		(9 "F.Adhes" user "F.Adhesive")
		(11 "B.Adhes" user "B.Adhesive")
		(13 "F.Paste" user "Package Geometry/Pastemask Top")
		(15 "B.Paste" user "Package Geometry/Pastemask Bottom")
		(5 "F.SilkS" user "Ref Des/Silkscreen Top")
		(7 "B.SilkS" user "Ref Des/Silkscreen Bottom")
		(1 "F.Mask" user "Board Geometry/Soldermask Top")
		(3 "B.Mask" user "Board Geometry/Soldermask Bottom")
		(17 "Dwgs.User" user "User.Drawings")
		(19 "Cmts.User" user "User.Comments")
		(21 "Eco1.User" user "User.Eco1")
		(23 "Eco2.User" user "User.Eco2")
		(25 "Edge.Cuts" user "Board Geometry/Outline")
		(27 "Margin" user)
		(31 "F.CrtYd" user "Package Geometry/Place Bound Top")
		(29 "B.CrtYd" user "Package Geometry/Place Bound Bottom")
		(35 "F.Fab" user "Ref Des/Assembly Top")
		(33 "B.Fab" user "Ref Des/Assembly Bottom")
	)
	(footprint ""
		(layer "F.Cu")
		(at 444.922148 -227.908866 180)
		(property "Reference" "R6609"
			(at 0 0 180)
			(layer "F.SilkS")
			(hide yes)
			(effects
				(font
					(size 1.27 1.27)
				)
			)
		)
		(property "Value" ""
			(at 0 0 180)
			(layer "F.Fab")
			(effects
				(font
					(size 1.27 1.27)
				)
			)
		)
		(duplicate_pad_numbers_are_jumpers no)
		(fp_line
			(start 0.7874 0.4064)
			(end -0.7874 0.4064)
			(stroke
				(width 0.1524)
				(type default)
			)
			(layer "F.SilkS")
		)
		(fp_line
			(start 0.7874 -0.4064)
			(end 0.7874 0.4064)
			(stroke
				(width 0.1524)
				(type default)
			)
			(layer "F.SilkS")
		)
		(fp_line
			(start -0.7874 0.4064)
			(end -0.7874 -0.4064)
			(stroke
				(width 0.1524)
				(type default)
			)
			(layer "F.SilkS")
		)
		(fp_line
			(start -0.7874 -0.4064)
			(end 0.7874 -0.4064)
			(stroke
				(width 0.1524)
				(type default)
			)
			(layer "F.SilkS")
		)
		(fp_line
			(start 0.67945 0.3048)
			(end 0.120396 0.3048)
			(stroke
				(width 0.1)
				(type default)
			)
			(layer "F.Fab")
		)
		(fp_line
			(start 0.67945 -0.3048)
			(end 0.67945 0.3048)
			(stroke
				(width 0.1)
				(type default)
			)
			(layer "F.Fab")
		)
		(fp_line
			(start 0.12065 -0.2794)
			(end 0.12065 -0.3048)
			(stroke
				(width 0.1)
				(type default)
			)
			(layer "F.Fab")
		)
		(fp_line
			(start 0.12065 -0.3048)
			(end 0.67945 -0.3048)
			(stroke
				(width 0.1)
				(type default)
			)
			(layer "F.Fab")
		)
		(fp_line
			(start 0.120396 0.3048)
			(end 0.120396 0.2794)
			(stroke
				(width 0.1)
				(type default)
			)
			(layer "F.Fab")
		)
		(fp_line
			(start 0.120396 0.2794)
			(end -0.12065 0.2794)
			(stroke
				(width 0.1)
				(type default)
			)
			(layer "F.Fab")
		)
		(fp_line
			(start -0.12065 0.3048)
			(end -0.67945 0.3048)
			(stroke
				(width 0.1)
				(type default)
			)
			(layer "F.Fab")
		)
		(fp_line
			(start -0.12065 0.2794)
			(end -0.12065 0.3048)
			(stroke
				(width 0.1)
				(type default)
			)
			(layer "F.Fab")
		)
		(fp_line
			(start -0.12065 -0.2794)
			(end 0.12065 -0.2794)
			(stroke
				(width 0.1)
				(type default)
			)
			(layer "F.Fab")
		)
		(fp_line
			(start -0.12065 -0.305054)
			(end -0.12065 -0.2794)
			(stroke
				(width 0.1)
				(type default)
			)
			(layer "F.Fab")
		)
		(fp_line
			(start -0.67945 0.3048)
			(end -0.67945 -0.305054)
			(stroke
				(width 0.1)
				(type default)
			)
			(layer "F.Fab")
		)
		(fp_line
			(start -0.67945 -0.305054)
			(end -0.12065 -0.305054)
			(stroke
				(width 0.1)
				(type default)
			)
			(layer "F.Fab")
		)
		(pad "1" smd circle
			(at -0.40005 0 180)
			(size 0 0)
			(layers "F.Cu" "F.Mask" "F.Paste")
			(net "UART_PEX3_SDB_CP2108_RX")
		)
		(pad "2" smd circle
			(at 0.40005 0 180)
			(size 0 0)
			(layers "F.Cu" "F.Mask" "F.Paste")
			(net "UART_PEX3_SDB_R_RX")
		)
	)
	(footprint ""
		(layer "F.Cu")
		(at 226.701858 -176.306226)
		(property "Reference" "U359"
			(at -1.8034 -1.793748 0)
			(unlocked yes)
			(layer "F.SilkS")
			(effects
				(font
					(size 0.7874 0.5842)
					(thickness 0.1524)
				)
				(justify left)
			)
		)
		(property "Value" ""
			(at 0 0 0)
			(layer "F.Fab")
			(effects
				(font
					(size 1.27 1.27)
				)
			)
		)
		(duplicate_pad_numbers_are_jumpers no)
		(fp_line
			(start -1.640078 -1.100074)
			(end -1.640078 1.100074)
			(stroke
				(width 0.1524)
				(type default)
			)
			(layer "F.SilkS")
		)
		(fp_line
			(start -1.640078 1.100074)
			(end 1.640078 1.100074)
			(stroke
				(width 0.1524)
				(type default)
			)
			(layer "F.SilkS")
		)
		(fp_line
			(start 1.640078 -1.100074)
			(end -1.640078 -1.100074)
			(stroke
				(width 0.1524)
				(type default)
			)
			(layer "F.SilkS")
		)
		(fp_line
			(start 1.640078 1.100074)
			(end 1.640078 -1.100074)
			(stroke
				(width 0.1524)
				(type default)
			)
			(layer "F.SilkS")
		)
		(fp_poly
			(pts
				(xy -1.82753 -1.354582) (xy -2.643886 -1.626616) (xy -2.099818 -2.170684)
			)
			(stroke
				(width 0)
				(type default)
			)
			(fill yes)
			(layer "F.SilkS")
		)
		(fp_line
			(start -0.674878 -1.100074)
			(end -0.674878 1.100074)
			(stroke
				(width 0.1)
				(type default)
			)
			(layer "F.Fab")
		)
		(fp_line
			(start -0.674878 1.100074)
			(end 0.674878 1.100074)
			(stroke
				(width 0.1)
				(type default)
			)
			(layer "F.Fab")
		)
		(fp_line
			(start 0.674878 -1.100074)
			(end -0.674878 -1.100074)
			(stroke
				(width 0.1)
				(type default)
			)
			(layer "F.Fab")
		)
		(fp_line
			(start 0.674878 1.100074)
			(end 0.674878 -1.100074)
			(stroke
				(width 0.1)
				(type default)
			)
			(layer "F.Fab")
		)
		(fp_poly
			(pts
				(xy -1.74879 -0.649986) (xy -2.51841 -0.265176) (xy -2.51841 -1.034796)
			)
			(stroke
				(width 0)
				(type default)
			)
			(fill yes)
			(layer "F.Fab")
		)
		(pad "1" smd rect
			(at -0.818896 -0.649986 270)
			(size 0.3556 1.4732)
			(layers "F.Cu" "F.Mask" "F.Paste")
			(net "ADM1085_CEXT")
		)
		(pad "2" smd rect
			(at -0.818896 0 270)
			(size 0.3556 1.4732)
			(layers "F.Cu" "F.Mask" "F.Paste")
			(net "GND")
		)
		(pad "3" smd rect
			(at -0.818896 0.649986 270)
			(size 0.3556 1.4732)
			(layers "F.Cu" "F.Mask" "F.Paste")
			(net "ADM1085_IN")
		)
		(pad "4" smd rect
			(at 0.818896 0.649986 270)
			(size 0.3556 1.4732)
			(layers "F.Cu" "F.Mask" "F.Paste")
			(net "ADM1085_ENOUT")
		)
		(pad "5" smd rect
			(at 0.818896 0 270)
			(size 0.3556 1.4732)
			(layers "F.Cu" "F.Mask" "F.Paste")
			(net "THRESHOLD")
		)
		(pad "6" smd rect
			(at 0.818896 -0.649986 270)
			(size 0.3556 1.4732)
			(layers "F.Cu" "F.Mask" "F.Paste")
			(net "P3V3_AUX")
		)
	)
	(footprint ""
		(layer "F.Cu")
		(at 20.575524 -69.47916 180)
		(property "Reference" "PU76"
			(at -1.921764 3.80238 90)
			(unlocked yes)
			(layer "F.SilkS")
			(effects
				(font
					(size 0.7874 0.5842)
					(thickness 0.1524)
				)
			)
		)
		(property "Value" ""
			(at 0 0 180)
			(layer "F.Fab")
			(effects
				(font
					(size 1.27 1.27)
				)
			)
		)
		(duplicate_pad_numbers_are_jumpers no)
		(fp_line
			(start 1.239774 1.495298)
			(end -1.239774 1.495298)
			(stroke
				(width 0.1524)
				(type default)
			)
			(layer "F.SilkS")
		)
		(fp_line
			(start 1.239774 -1.495298)
			(end 1.239774 1.495298)
			(stroke
				(width 0.1524)
				(type default)
			)
			(layer "F.SilkS")
		)
		(fp_line
			(start -1.239774 1.495298)
			(end -1.239774 -1.495298)
			(stroke
				(width 0.1524)
				(type default)
			)
			(layer "F.SilkS")
		)
		(fp_line
			(start -1.239774 -1.495298)
			(end 1.239774 -1.495298)
			(stroke
				(width 0.1524)
				(type default)
			)
			(layer "F.SilkS")
		)
		(fp_poly
			(pts
				(xy -1.825498 -1.322832) (xy -2.54381 -0.604266) (xy -1.466342 -0.24511)
			)
			(stroke
				(width 0)
				(type default)
			)
			(fill yes)
			(layer "F.SilkS")
		)
		(fp_line
			(start 0.8001 1.050036)
			(end -0.8001 1.050036)
			(stroke
				(width 0.1)
				(type default)
			)
			(layer "F.Fab")
		)
		(fp_line
			(start 0.8001 -1.050036)
			(end 0.8001 1.050036)
			(stroke
				(width 0.1)
				(type default)
			)
			(layer "F.Fab")
		)
		(fp_line
			(start -0.8001 1.050036)
			(end -0.8001 -1.050036)
			(stroke
				(width 0.1)
				(type default)
			)
			(layer "F.Fab")
		)
		(fp_line
			(start -0.8001 -1.050036)
			(end 0.8001 -1.050036)
			(stroke
				(width 0.1)
				(type default)
			)
			(layer "F.Fab")
		)
		(fp_poly
			(pts
				(xy -2.458974 -0.508) (xy -2.458974 0.508) (xy -1.442974 0)
			)
			(stroke
				(width 0)
				(type default)
			)
			(fill yes)
			(layer "F.Fab")
		)
		(pad "1_2" smd circle
			(at -0.374904 0 270)
			(size 0 0)
			(layers "F.Cu" "F.Mask" "F.Paste")
			(net "P12V_AUX")
		)
		(pad "3" smd rect
			(at -0.499872 0.999998 180)
			(size 0.254 0.7112)
			(layers "F.Cu" "F.Mask" "F.Paste")
			(net "GND")
		)
		(pad "4" smd rect
			(at 0 0.999998 180)
			(size 0.254 0.7112)
			(layers "F.Cu" "F.Mask" "F.Paste")
			(net "P12V_SSD0_CO_ILIMIT")
		)
		(pad "5" smd rect
			(at 0.499872 0.999998 180)
			(size 0.254 0.7112)
			(layers "F.Cu" "F.Mask" "F.Paste")
			(net "P12V_SSD0_CO_MODE")
		)
		(pad "6_7" smd circle
			(at 0.374904 0 90)
			(size 0 0)
			(layers "F.Cu" "F.Mask" "F.Paste")
			(net "P12V_SSD0_R")
		)
		(pad "8" smd rect
			(at 0.499872 -0.999998 180)
			(size 0.254 0.7112)
			(layers "F.Cu" "F.Mask" "F.Paste")
			(net "P12V_SSD0_CO_GATE")
		)
		(pad "9" smd rect
			(at 0 -0.999998 180)
			(size 0.254 0.7112)
			(layers "F.Cu" "F.Mask" "F.Paste")
			(net "P12V_SSD0_CO_EN")
		)
		(pad "10" smd rect
			(at -0.499872 -0.999998 180)
			(size 0.254 0.7112)
			(layers "F.Cu" "F.Mask" "F.Paste")
			(net "P12V_SSD0_CO_DV_DT")
		)
	)
	(footprint ""
		(layer "F.Cu")
		(at 302.14697 -55.63489 90)
		(property "Reference" "PC872"
			(at 0 0 90)
			(layer "F.SilkS")
			(hide yes)
			(effects
				(font
					(size 1.27 1.27)
				)
			)
		)
		(property "Value" ""
			(at 0 0 90)
			(layer "F.Fab")
			(effects
				(font
					(size 1.27 1.27)
				)
			)
		)
		(duplicate_pad_numbers_are_jumpers no)
		(fp_line
			(start 1.524 -0.762)
			(end 1.524 0.762)
			(stroke
				(width 0.1524)
				(type default)
			)
			(layer "F.SilkS")
		)
		(fp_line
			(start -1.524 -0.762)
			(end 1.524 -0.762)
			(stroke
				(width 0.1524)
				(type default)
			)
			(layer "F.SilkS")
		)
		(fp_line
			(start 1.524 0.762)
			(end -1.524 0.762)
			(stroke
				(width 0.1524)
				(type default)
			)
			(layer "F.SilkS")
		)
		(fp_line
			(start -1.524 0.762)
			(end -1.524 -0.762)
			(stroke
				(width 0.1524)
				(type default)
			)
			(layer "F.SilkS")
		)
		(fp_line
			(start 1.1049 -0.724916)
			(end -1.1049 -0.724916)
			(stroke
				(width 0.1)
				(type default)
			)
			(layer "F.Fab")
		)
		(fp_line
			(start -1.1049 -0.724916)
			(end -1.1049 0.724916)
			(stroke
				(width 0.1)
				(type default)
			)
			(layer "F.Fab")
		)
		(fp_line
			(start 1.1049 0.724916)
			(end 1.1049 -0.724916)
			(stroke
				(width 0.1)
				(type default)
			)
			(layer "F.Fab")
		)
		(fp_line
			(start -1.1049 0.724916)
			(end 1.1049 0.724916)
			(stroke
				(width 0.1)
				(type default)
			)
			(layer "F.Fab")
		)
		(pad "1" smd rect
			(at -0.889 0 270)
			(size 1.016 1.27)
			(layers "F.Cu" "F.Mask" "F.Paste")
			(net "P12V_SSD10_R")
		)
		(pad "2" smd rect
			(at 0.889 0 270)
			(size 1.016 1.27)
			(layers "F.Cu" "F.Mask" "F.Paste")
			(net "GND")
		)
	)
	(footprint ""
		(layer "F.Cu")
		(at 328.168 -227.711 90)
		(property "Reference" "R4169"
			(at 0 0 90)
			(layer "F.SilkS")
			(hide yes)
			(effects
				(font
					(size 1.27 1.27)
				)
			)
		)
		(property "Value" ""
			(at 0 0 90)
			(layer "F.Fab")
			(effects
				(font
					(size 1.27 1.27)
				)
			)
		)
		(duplicate_pad_numbers_are_jumpers no)
		(fp_line
			(start 0.7874 -0.4064)
			(end 0.7874 0.4064)
			(stroke
				(width 0.1524)
				(type default)
			)
			(layer "F.SilkS")
		)
		(fp_line
			(start -0.7874 -0.4064)
			(end 0.7874 -0.4064)
			(stroke
				(width 0.1524)
				(type default)
			)
			(layer "F.SilkS")
		)
		(fp_line
			(start 0.7874 0.4064)
			(end -0.7874 0.4064)
			(stroke
				(width 0.1524)
				(type default)
			)
			(layer "F.SilkS")
		)
		(fp_line
			(start -0.7874 0.4064)
			(end -0.7874 -0.4064)
			(stroke
				(width 0.1524)
				(type default)
			)
			(layer "F.SilkS")
		)
		(fp_line
			(start -0.12065 -0.305054)
			(end -0.12065 -0.2794)
			(stroke
				(width 0.1)
				(type default)
			)
			(layer "F.Fab")
		)
		(fp_line
			(start -0.67945 -0.305054)
			(end -0.12065 -0.305054)
			(stroke
				(width 0.1)
				(type default)
			)
			(layer "F.Fab")
		)
		(fp_line
			(start 0.67945 -0.3048)
			(end 0.67945 0.3048)
			(stroke
				(width 0.1)
				(type default)
			)
			(layer "F.Fab")
		)
		(fp_line
			(start 0.12065 -0.3048)
			(end 0.67945 -0.3048)
			(stroke
				(width 0.1)
				(type default)
			)
			(layer "F.Fab")
		)
		(fp_line
			(start 0.12065 -0.2794)
			(end 0.12065 -0.3048)
			(stroke
				(width 0.1)
				(type default)
			)
			(layer "F.Fab")
		)
		(fp_line
			(start -0.12065 -0.2794)
			(end 0.12065 -0.2794)
			(stroke
				(width 0.1)
				(type default)
			)
			(layer "F.Fab")
		)
		(fp_line
			(start 0.120396 0.2794)
			(end -0.12065 0.2794)
			(stroke
				(width 0.1)
				(type default)
			)
			(layer "F.Fab")
		)
		(fp_line
			(start -0.12065 0.2794)
			(end -0.12065 0.3048)
			(stroke
				(width 0.1)
				(type default)
			)
			(layer "F.Fab")
		)
		(fp_line
			(start 0.67945 0.3048)
			(end 0.120396 0.3048)
			(stroke
				(width 0.1)
				(type default)
			)
			(layer "F.Fab")
		)
		(fp_line
			(start 0.120396 0.3048)
			(end 0.120396 0.2794)
			(stroke
				(width 0.1)
				(type default)
			)
			(layer "F.Fab")
		)
		(fp_line
			(start -0.12065 0.3048)
			(end -0.67945 0.3048)
			(stroke
				(width 0.1)
				(type default)
			)
			(layer "F.Fab")
		)
		(fp_line
			(start -0.67945 0.3048)
			(end -0.67945 -0.305054)
			(stroke
				(width 0.1)
				(type default)
			)
			(layer "F.Fab")
		)
		(pad "1" smd circle
			(at -0.40005 0 90)
			(size 0 0)
			(layers "F.Cu" "F.Mask" "F.Paste")
			(net "RST_PEX_SYS_N")
		)
		(pad "2" smd circle
			(at 0.40005 0 90)
			(size 0 0)
			(layers "F.Cu" "F.Mask" "F.Paste")
			(net "RST_PEX_SYS_R_N")
		)
	)
	(footprint ""
		(layer "F.Cu")
		(at 41.069768 -356.244906 90)
		(property "Reference" "C169"
			(at 0 0 90)
			(layer "F.SilkS")
			(hide yes)
			(effects
				(font
					(size 1.27 1.27)
				)
			)
		)
		(property "Value" ""
			(at 0 0 90)
			(layer "F.Fab")
			(effects
				(font
					(size 1.27 1.27)
				)
			)
		)
		(duplicate_pad_numbers_are_jumpers no)
		(fp_line
			(start 0.299974 -0.150114)
			(end 0.299974 0.150114)
			(stroke
				(width 0.1)
				(type default)
			)
			(layer "F.Fab")
		)
		(fp_line
			(start -0.299974 -0.150114)
			(end 0.299974 -0.150114)
			(stroke
				(width 0.1)
				(type default)
			)
			(layer "F.Fab")
		)
		(fp_line
			(start 0.299974 0.150114)
			(end -0.299974 0.150114)
			(stroke
				(width 0.1)
				(type default)
			)
			(layer "F.Fab")
		)
		(fp_line
			(start -0.299974 0.150114)
			(end -0.299974 -0.150114)
			(stroke
				(width 0.1)
				(type default)
			)
			(layer "F.Fab")
		)
		(pad "1" smd rect
			(at -0.2667 0 90)
			(size 0.3048 0.381)
			(layers "F.Cu" "F.Mask" "F.Paste")
			(net "P5E_PEX0_STN7_TX_DP<123>")
		)
		(pad "2" smd rect
			(at 0.2667 0 90)
			(size 0.3048 0.381)
			(layers "F.Cu" "F.Mask" "F.Paste")
			(net "P5E_PEX0_STN7_TX_C_DP<123>")
		)
	)
	(footprint ""
		(layer "F.Cu")
		(at 37.960808 -343.952322 90)
		(property "Reference" "C2168"
			(at 0 0 90)
			(layer "F.SilkS")
			(hide yes)
			(effects
				(font
					(size 1.27 1.27)
				)
			)
		)
		(property "Value" ""
			(at 0 0 90)
			(layer "F.Fab")
			(effects
				(font
					(size 1.27 1.27)
				)
			)
		)
		(duplicate_pad_numbers_are_jumpers no)
		(fp_line
			(start 0.299974 -0.150114)
			(end 0.299974 0.150114)
			(stroke
				(width 0.1)
				(type default)
			)
			(layer "F.Fab")
		)
		(fp_line
			(start -0.299974 -0.150114)
			(end 0.299974 -0.150114)
			(stroke
				(width 0.1)
				(type default)
			)
			(layer "F.Fab")
		)
		(fp_line
			(start 0.299974 0.150114)
			(end -0.299974 0.150114)
			(stroke
				(width 0.1)
				(type default)
			)
			(layer "F.Fab")
		)
		(fp_line
			(start -0.299974 0.150114)
			(end -0.299974 -0.150114)
			(stroke
				(width 0.1)
				(type default)
			)
			(layer "F.Fab")
		)
		(pad "1" smd rect
			(at -0.2667 0 90)
			(size 0.3048 0.381)
			(layers "F.Cu" "F.Mask" "F.Paste")
			(net "P5E_PEX0_STN4_TX_DP<71>")
		)
		(pad "2" smd rect
			(at 0.2667 0 90)
			(size 0.3048 0.381)
			(layers "F.Cu" "F.Mask" "F.Paste")
			(net "P5E_PEX0_STN4_TX_C_DP<71>")
		)
	)
)
